# TIMECARD (Time Appliance Project (Time Card)) — schematic netlist excerpt (pin names and nets, part order shuffled) for the footprints in the layout excerpt that follows; sources: Cadence DE-HDL packaged netlist, KiCad conversion of R4006-B0001-02_R01.brd

C198  CAPACITOR  4.7UF 6.3V 20%  pkg SMC_0402R_H026  page 10 : \1\ = XP3R3V_FPGA ; \2\ = SG
C176  CAPACITOR  100UF 6.3V 20%  pkg SMC_1210R_H110  page 14 : \1\ = XP1R0V_FPGA_VCCINT ; \2\ = SG
TP136  TP_PIONT  pkg TP010CT020B030_PTH  page 25 : \1\ = IO_L22P_34

(kicad_pcb
	(version 20260206)
	(generator "pcbnew")
	(generator_version "10.0")
	(general
		(thickness 1.6)
		(legacy_teardrops no)
	)
	(paper "A4")
	(title_block
		(title "timecard-production-celestica-r4006 — R4006-B0001-02_R01.brd")
		(comment 1 "Time Appliance Project (Time Card) / footprints 639-641 of 1113")
	)
	(layers
		(0 "F.Cu" signal "TOP")
		(4 "In1.Cu" signal "L02_GND1")
		(6 "In2.Cu" signal "L03_SIG1")
		(8 "In3.Cu" signal "L04_GND2")
		(10 "In4.Cu" signal "L05_VCC1")
		(12 "In5.Cu" signal "L06_VCC2")
		(14 "In6.Cu" signal "L07_GND3")
		(16 "In7.Cu" signal "L08_SIG2")
		(18 "In8.Cu" signal "L09_GND4")
		(2 "B.Cu" signal "BOTTOM")
		(9 "F.Adhes" user "F.Adhesive")
		(11 "B.Adhes" user "B.Adhesive")
		(13 "F.Paste" user "Package Geometry/Pastemask Top")
		(15 "B.Paste" user "Package Geometry/Pastemask Bottom")
		(5 "F.SilkS" user "Ref Des/Silkscreen Top")
		(7 "B.SilkS" user "Ref Des/Silkscreen Bottom")
		(1 "F.Mask" user "Board Geometry/Soldermask Top")
		(3 "B.Mask" user "Board Geometry/Soldermask Bottom")
		(17 "Dwgs.User" user "User.Drawings")
		(19 "Cmts.User" user "User.Comments")
		(21 "Eco1.User" user "User.Eco1")
		(23 "Eco2.User" user "User.Eco2")
		(25 "Edge.Cuts" user "Board Geometry/Outline")
		(27 "Margin" user)
		(31 "F.CrtYd" user "Package Geometry/Place Bound Top")
		(29 "B.CrtYd" user "Package Geometry/Place Bound Bottom")
		(35 "F.Fab" user "Ref Des/Assembly Top")
		(33 "B.Fab" user "Ref Des/Assembly Bottom")
	)
	(footprint ""
		(layer "F.Cu")
		(at 123.19 -39.116)
		(property "Reference" "TP136"
			(at -0.73025 0.8128 90)
			(unlocked yes)
			(layer "F.SilkS")
			(effects
				(font
					(size 0.635 0.4064)
					(thickness 0.1524)
				)
				(justify left)
			)
		)
		(property "Value" ""
			(at 0 0 0)
			(layer "F.Fab")
			(effects
				(font
					(size 1.27 1.27)
				)
			)
		)
		(property "Device Type" "TP_PIONT-TP010CT020B030_PTH-TPA"
			(at -1.341882 0.996696 0)
			(unlocked yes)
			(layer "F.Fab")
			(hide yes)
			(effects
				(font
					(size 0.7874 0.5842)
					(thickness 0.1524)
				)
				(justify left)
			)
		)
		(duplicate_pad_numbers_are_jumpers no)
		(fp_poly
			(pts
				(arc
					(start 0.889 0)
					(mid -0.889 0)
					(end 0.889 0)
				)
			)
			(stroke
				(width 0)
				(type default)
			)
			(fill no)
			(layer "B.CrtYd")
		)
		(fp_poly
			(pts
				(arc
					(start 0.889 0)
					(mid -0.889 0)
					(end 0.889 0)
				)
			)
			(stroke
				(width 0)
				(type default)
			)
			(fill no)
			(layer "F.CrtYd")
		)
		(pad "1" thru_hole circle
			(at 0 0)
			(size 0.508 0.508)
			(drill 0.254)
			(layers "*.Cu" "*.Mask")
			(remove_unused_layers no)
			(net "IO_L22P_34")
			(clearance 0.1016)
			(padstack
				(mode front_inner_back)
				(layer "Inner"
					(shape circle)
					(size 0.508 0.508)
					(clearance 0.1016)
				)
				(layer "B.Cu"
					(shape circle)
					(size 0.762 0.762)
					(clearance -0.0254)
				)
			)
		)
	)
	(footprint ""
		(layer "F.Cu")
		(at 133.223 -34.163)
		(property "Reference" "C176"
			(at 4.445 1.94437 0)
			(unlocked yes)
			(layer "F.SilkS")
			(effects
				(font
					(size 0.7874 0.5842)
					(thickness 0.1524)
				)
			)
		)
		(property "Value" "VAL*"
			(at 0.1016 3.769106 0)
			(unlocked yes)
			(layer "F.Fab")
			(hide yes)
			(effects
				(font
					(size 0.7874 0.5842)
					(thickness 0.1524)
				)
			)
		)
		(property "Tolerance" "TOL*"
			(at 0.127 4.734306 0)
			(unlocked yes)
			(layer "Cmts.User")
			(hide yes)
			(effects
				(font
					(size 0.7874 0.5842)
					(thickness 0.1524)
				)
			)
		)
		(property "User Part Number" "PARTNUM*"
			(at 0.2032 5.801106 0)
			(unlocked yes)
			(layer "Cmts.User")
			(hide yes)
			(effects
				(font
					(size 0.7874 0.5842)
					(thickness 0.1524)
				)
			)
		)
		(property "Device Type" "CAPACITOR-G109-0G107-BM,100UF,A"
			(at 0.0762 2.829306 0)
			(unlocked yes)
			(layer "F.Fab")
			(hide yes)
			(effects
				(font
					(size 0.7874 0.5842)
					(thickness 0.1524)
				)
			)
		)
		(duplicate_pad_numbers_are_jumpers no)
		(fp_line
			(start -2.159 -1.5748)
			(end 2.159 -1.5748)
			(stroke
				(width 0.1)
				(type default)
			)
			(layer "F.SilkS")
		)
		(fp_line
			(start -2.159 1.5748)
			(end -2.159 -1.5748)
			(stroke
				(width 0.1)
				(type default)
			)
			(layer "F.SilkS")
		)
		(fp_line
			(start 2.159 -1.5748)
			(end 2.159 1.5748)
			(stroke
				(width 0.1)
				(type default)
			)
			(layer "F.SilkS")
		)
		(fp_line
			(start 2.159 1.5748)
			(end -2.159 1.5748)
			(stroke
				(width 0.1)
				(type default)
			)
			(layer "F.SilkS")
		)
		(fp_rect
			(start 2.159 1.5748)
			(end -2.159 -1.5748)
			(stroke
				(width 0)
				(type default)
			)
			(fill no)
			(layer "F.CrtYd")
		)
		(fp_line
			(start -1.6002 -1.2446)
			(end -1.6002 1.2446)
			(stroke
				(width 0.1)
				(type default)
			)
			(layer "F.Fab")
		)
		(fp_line
			(start -1.6002 1.2446)
			(end 1.6002 1.2446)
			(stroke
				(width 0.1)
				(type default)
			)
			(layer "F.Fab")
		)
		(fp_line
			(start 1.6002 -1.2446)
			(end -1.6002 -1.2446)
			(stroke
				(width 0.1)
				(type default)
			)
			(layer "F.Fab")
		)
		(fp_line
			(start 1.6002 1.2446)
			(end 1.6002 -1.2446)
			(stroke
				(width 0.1)
				(type default)
			)
			(layer "F.Fab")
		)
		(pad "1" smd rect
			(at -1.3335 0)
			(size 1.143 2.6416)
			(layers "F.Cu" "F.Mask" "F.Paste")
			(net "XP1R0V_FPGA_VCCINT")
		)
		(pad "2" smd rect
			(at 1.3335 0)
			(size 1.143 2.6416)
			(layers "F.Cu" "F.Mask" "F.Paste")
			(net "SG")
		)
		(zone
			(layer "F.Cu")
			(hatch none 0.5)
			(connect_pads
				(clearance 0)
			)
			(min_thickness 0.25)
			(keepout
				(tracks allowed)
				(vias not_allowed)
				(pads allowed)
				(copperpour not_allowed)
				(footprints allowed)
			)
			(placement
				(enabled no)
				(sheetname "")
			)
			(fill
				(thermal_gap 0.5)
				(thermal_bridge_width 0.5)
				(island_removal_mode 0)
			)
			(polygon
				(pts
					(xy 133.9088 -32.766) (xy 133.9088 -35.56) (xy 132.5372 -35.56) (xy 132.5372 -32.766)
				)
			)
		)
	)
	(footprint ""
		(layer "F.Cu")
		(at 90.9828 -70.6628 -90)
		(property "Reference" "C198"
			(at -18.6182 27.44343 90)
			(unlocked yes)
			(layer "F.SilkS")
			(effects
				(font
					(size 0.7874 0.5842)
					(thickness 0.1524)
				)
			)
		)
		(property "Value" "VAL*"
			(at 0.02032 2.13233 270)
			(unlocked yes)
			(layer "F.Fab")
			(hide yes)
			(effects
				(font
					(size 0.7874 0.5842)
					(thickness 0.1524)
				)
			)
		)
		(property "Tolerance" "TOL*"
			(at 0.044704 3.05435 270)
			(unlocked yes)
			(layer "Cmts.User")
			(hide yes)
			(effects
				(font
					(size 0.7874 0.5842)
					(thickness 0.1524)
				)
			)
		)
		(property "User Part Number" "PARTNUM*"
			(at 0.02032 4.024884 270)
			(unlocked yes)
			(layer "Cmts.User")
			(hide yes)
			(effects
				(font
					(size 0.7874 0.5842)
					(thickness 0.1524)
				)
			)
		)
		(property "Device Type" "CAPACITOR-G105-0F475-BM,4.7UF,A"
			(at 0.008382 1.210564 270)
			(unlocked yes)
			(layer "F.Fab")
			(hide yes)
			(effects
				(font
					(size 0.7874 0.5842)
					(thickness 0.1524)
				)
			)
		)
		(duplicate_pad_numbers_are_jumpers no)
		(fp_line
			(start -1.143 0.5588)
			(end 1.143 0.5588)
			(stroke
				(width 0.1)
				(type default)
			)
			(layer "F.SilkS")
		)
		(fp_line
			(start 1.143 0.5588)
			(end 1.143 -0.5588)
			(stroke
				(width 0.1)
				(type default)
			)
			(layer "F.SilkS")
		)
		(fp_line
			(start -1.143 -0.5588)
			(end -1.143 0.5588)
			(stroke
				(width 0.1)
				(type default)
			)
			(layer "F.SilkS")
		)
		(fp_line
			(start 1.143 -0.5588)
			(end -1.143 -0.5588)
			(stroke
				(width 0.1)
				(type default)
			)
			(layer "F.SilkS")
		)
		(fp_rect
			(start 1.143 0.5588)
			(end -1.143 -0.5588)
			(stroke
				(width 0)
				(type default)
			)
			(fill no)
			(layer "F.CrtYd")
		)
		(fp_line
			(start -0.508 0.3048)
			(end 0.508 0.3048)
			(stroke
				(width 0.1)
				(type default)
			)
			(layer "F.Fab")
		)
		(fp_line
			(start 0.508 0.3048)
			(end 0.508 -0.3048)
			(stroke
				(width 0.1)
				(type default)
			)
			(layer "F.Fab")
		)
		(fp_line
			(start -0.508 -0.3048)
			(end -0.508 0.3048)
			(stroke
				(width 0.1)
				(type default)
			)
			(layer "F.Fab")
		)
		(fp_line
			(start 0.508 -0.3048)
			(end -0.508 -0.3048)
			(stroke
				(width 0.1)
				(type default)
			)
			(layer "F.Fab")
		)
		(pad "1" smd rect
			(at -0.5334 0 270)
			(size 0.7112 0.6096)
			(layers "F.Cu" "F.Mask" "F.Paste")
			(net "XP3R3V_FPGA")
		)
		(pad "2" smd rect
			(at 0.5334 0 270)
			(size 0.7112 0.6096)
			(layers "F.Cu" "F.Mask" "F.Paste")
			(net "SG")
		)
		(zone
			(layer "F.Cu")
			(hatch none 0.5)
			(connect_pads
				(clearance 0)
			)
			(min_thickness 0.25)
			(keepout
				(tracks allowed)
				(vias not_allowed)
				(pads allowed)
				(copperpour not_allowed)
				(footprints allowed)
			)
			(placement
				(enabled no)
				(sheetname "")
			)
			(fill
				(thermal_gap 0.5)
				(thermal_bridge_width 0.5)
				(island_removal_mode 0)
			)
			(polygon
				(pts
					(xy 90.678 -70.5866) (xy 91.2876 -70.5866) (xy 91.2876 -70.739) (xy 90.678 -70.739)
				)
			)
		)
	)
)
